# S9S_MB_2U (Grand Teton) — schematic netlist excerpt (pin names and nets, part order shuffled) for the footprints in the layout excerpt that follows; sources: Cadence DE-HDL packaged netlist, KiCad conversion of 03242023_DA0F0TMBIJ0_F0T_Motherboard_J_brd_V01_OCP.brd

R1147  Q_RES  0 5% CHIP  pkg 0402LF  page 156 : A = HP_LVC3_OCP_V3_1_PRSNT2_N_R ; B = HP_LVC3_OCP_V3_1_ATTN_OUT_SW_N
R1090  Q_RES  2.2K 5% CHIP  pkg 0402LF  page 231 : A = P3V3_AUX ; B = SMB_SENSOR_M2_P0_3V3AUX_SDA
H98  HOLE  EMPTY  pkg TH  page 311 : \1\ = GND
C808  Q_CAP_DIFFBUS  DIFF BUS_0.22UF 6.3V 20% X6S  pkg C0201  page 175 : \1\ = P5E_CPU1_PE1_TX_C_DN<14> ; \2\ = P5E_CPU1_PE1_TX_DN<14>

(kicad_pcb
	(version 20260206)
	(generator "pcbnew")
	(generator_version "10.0")
	(general
		(thickness 1.6)
		(legacy_teardrops no)
	)
	(paper "A4")
	(title_block
		(title "03242023_DA0F0TMBIJ0_F0T_Motherboard_J_brd_V01_OCP.brd")
		(comment 1 "Grand Teton / footprints 1388-1391 of 6105")
	)
	(layers
		(0 "F.Cu" signal "TOP")
		(4 "In1.Cu" signal "GND")
		(6 "In2.Cu" signal "IN1")
		(8 "In3.Cu" signal "GND1")
		(10 "In4.Cu" signal "IN2")
		(12 "In5.Cu" signal "GND2")
		(14 "In6.Cu" signal "IN3")
		(16 "In7.Cu" signal "GND3")
		(18 "In8.Cu" signal "VCC")
		(20 "In9.Cu" signal "VCC1")
		(22 "In10.Cu" signal "GND4")
		(24 "In11.Cu" signal "IN4")
		(26 "In12.Cu" signal "GND5")
		(28 "In13.Cu" signal "IN5")
		(30 "In14.Cu" signal "GND6")
		(32 "In15.Cu" signal "IN6")
		(34 "In16.Cu" signal "GND7")
		(2 "B.Cu" signal "BOTTOM")
		(9 "F.Adhes" user "F.Adhesive")
		(11 "B.Adhes" user "B.Adhesive")
		(13 "F.Paste" user "Package Geometry/Pastemask Top")
		(15 "B.Paste" user "Package Geometry/Pastemask Bottom")
		(5 "F.SilkS" user "Ref Des/Silkscreen Top")
		(7 "B.SilkS" user "Ref Des/Silkscreen Bottom")
		(1 "F.Mask" user "Board Geometry/Soldermask Top")
		(3 "B.Mask" user "Board Geometry/Soldermask Bottom")
		(17 "Dwgs.User" user "User.Drawings")
		(19 "Cmts.User" user "User.Comments")
		(21 "Eco1.User" user "User.Eco1")
		(23 "Eco2.User" user "User.Eco2")
		(25 "Edge.Cuts" user "Board Geometry/Outline")
		(27 "Margin" user)
		(31 "F.CrtYd" user "Package Geometry/Place Bound Top")
		(29 "B.CrtYd" user "Package Geometry/Place Bound Bottom")
		(35 "F.Fab" user "Ref Des/Assembly Top")
		(33 "B.Fab" user "Ref Des/Assembly Bottom")
	)
	(footprint ""
		(layer "F.Cu")
		(at 111.332772 -130.869182)
		(property "Reference" "R1090"
			(at 0 0 0)
			(layer "F.SilkS")
			(hide yes)
			(effects
				(font
					(size 1.27 1.27)
				)
			)
		)
		(property "Value" ""
			(at 0 0 0)
			(layer "F.Fab")
			(effects
				(font
					(size 1.27 1.27)
				)
			)
		)
		(duplicate_pad_numbers_are_jumpers no)
		(fp_line
			(start -0.7874 -0.4064)
			(end 0.7874 -0.4064)
			(stroke
				(width 0.1524)
				(type default)
			)
			(layer "F.SilkS")
		)
		(fp_line
			(start -0.7874 0.4064)
			(end -0.7874 -0.4064)
			(stroke
				(width 0.1524)
				(type default)
			)
			(layer "F.SilkS")
		)
		(fp_line
			(start 0.7874 -0.4064)
			(end 0.7874 0.4064)
			(stroke
				(width 0.1524)
				(type default)
			)
			(layer "F.SilkS")
		)
		(fp_line
			(start 0.7874 0.4064)
			(end -0.7874 0.4064)
			(stroke
				(width 0.1524)
				(type default)
			)
			(layer "F.SilkS")
		)
		(fp_line
			(start -0.67945 -0.305054)
			(end -0.12065 -0.305054)
			(stroke
				(width 0.1)
				(type default)
			)
			(layer "F.Fab")
		)
		(fp_line
			(start -0.67945 0.3048)
			(end -0.67945 -0.305054)
			(stroke
				(width 0.1)
				(type default)
			)
			(layer "F.Fab")
		)
		(fp_line
			(start -0.12065 -0.305054)
			(end -0.12065 -0.2794)
			(stroke
				(width 0.1)
				(type default)
			)
			(layer "F.Fab")
		)
		(fp_line
			(start -0.12065 -0.2794)
			(end 0.12065 -0.2794)
			(stroke
				(width 0.1)
				(type default)
			)
			(layer "F.Fab")
		)
		(fp_line
			(start -0.12065 0.2794)
			(end -0.12065 0.3048)
			(stroke
				(width 0.1)
				(type default)
			)
			(layer "F.Fab")
		)
		(fp_line
			(start -0.12065 0.3048)
			(end -0.67945 0.3048)
			(stroke
				(width 0.1)
				(type default)
			)
			(layer "F.Fab")
		)
		(fp_line
			(start 0.120396 0.2794)
			(end -0.12065 0.2794)
			(stroke
				(width 0.1)
				(type default)
			)
			(layer "F.Fab")
		)
		(fp_line
			(start 0.120396 0.3048)
			(end 0.120396 0.2794)
			(stroke
				(width 0.1)
				(type default)
			)
			(layer "F.Fab")
		)
		(fp_line
			(start 0.12065 -0.3048)
			(end 0.67945 -0.3048)
			(stroke
				(width 0.1)
				(type default)
			)
			(layer "F.Fab")
		)
		(fp_line
			(start 0.12065 -0.2794)
			(end 0.12065 -0.3048)
			(stroke
				(width 0.1)
				(type default)
			)
			(layer "F.Fab")
		)
		(fp_line
			(start 0.67945 -0.3048)
			(end 0.67945 0.3048)
			(stroke
				(width 0.1)
				(type default)
			)
			(layer "F.Fab")
		)
		(fp_line
			(start 0.67945 0.3048)
			(end 0.120396 0.3048)
			(stroke
				(width 0.1)
				(type default)
			)
			(layer "F.Fab")
		)
		(pad "1" smd circle
			(at -0.40005 0)
			(size 0 0)
			(layers "F.Cu" "F.Mask" "F.Paste")
			(net "P3V3_AUX")
		)
		(pad "2" smd circle
			(at 0.40005 0)
			(size 0 0)
			(layers "F.Cu" "F.Mask" "F.Paste")
			(net "SMB_SENSOR_M2_P0_3V3AUX_SDA")
		)
	)
	(footprint ""
		(layer "F.Cu")
		(at 461.720946 -102.41915)
		(property "Reference" "R1147"
			(at 0 0 0)
			(layer "F.SilkS")
			(hide yes)
			(effects
				(font
					(size 1.27 1.27)
				)
			)
		)
		(property "Value" ""
			(at 0 0 0)
			(layer "F.Fab")
			(effects
				(font
					(size 1.27 1.27)
				)
			)
		)
		(duplicate_pad_numbers_are_jumpers no)
		(fp_line
			(start -0.7874 -0.4064)
			(end 0.7874 -0.4064)
			(stroke
				(width 0.1524)
				(type default)
			)
			(layer "F.SilkS")
		)
		(fp_line
			(start -0.7874 0.4064)
			(end -0.7874 -0.4064)
			(stroke
				(width 0.1524)
				(type default)
			)
			(layer "F.SilkS")
		)
		(fp_line
			(start 0.7874 -0.4064)
			(end 0.7874 0.4064)
			(stroke
				(width 0.1524)
				(type default)
			)
			(layer "F.SilkS")
		)
		(fp_line
			(start 0.7874 0.4064)
			(end -0.7874 0.4064)
			(stroke
				(width 0.1524)
				(type default)
			)
			(layer "F.SilkS")
		)
		(fp_line
			(start -0.67945 -0.305054)
			(end -0.12065 -0.305054)
			(stroke
				(width 0.1)
				(type default)
			)
			(layer "F.Fab")
		)
		(fp_line
			(start -0.67945 0.3048)
			(end -0.67945 -0.305054)
			(stroke
				(width 0.1)
				(type default)
			)
			(layer "F.Fab")
		)
		(fp_line
			(start -0.12065 -0.305054)
			(end -0.12065 -0.2794)
			(stroke
				(width 0.1)
				(type default)
			)
			(layer "F.Fab")
		)
		(fp_line
			(start -0.12065 -0.2794)
			(end 0.12065 -0.2794)
			(stroke
				(width 0.1)
				(type default)
			)
			(layer "F.Fab")
		)
		(fp_line
			(start -0.12065 0.2794)
			(end -0.12065 0.3048)
			(stroke
				(width 0.1)
				(type default)
			)
			(layer "F.Fab")
		)
		(fp_line
			(start -0.12065 0.3048)
			(end -0.67945 0.3048)
			(stroke
				(width 0.1)
				(type default)
			)
			(layer "F.Fab")
		)
		(fp_line
			(start 0.120396 0.2794)
			(end -0.12065 0.2794)
			(stroke
				(width 0.1)
				(type default)
			)
			(layer "F.Fab")
		)
		(fp_line
			(start 0.120396 0.3048)
			(end 0.120396 0.2794)
			(stroke
				(width 0.1)
				(type default)
			)
			(layer "F.Fab")
		)
		(fp_line
			(start 0.12065 -0.3048)
			(end 0.67945 -0.3048)
			(stroke
				(width 0.1)
				(type default)
			)
			(layer "F.Fab")
		)
		(fp_line
			(start 0.12065 -0.2794)
			(end 0.12065 -0.3048)
			(stroke
				(width 0.1)
				(type default)
			)
			(layer "F.Fab")
		)
		(fp_line
			(start 0.67945 -0.3048)
			(end 0.67945 0.3048)
			(stroke
				(width 0.1)
				(type default)
			)
			(layer "F.Fab")
		)
		(fp_line
			(start 0.67945 0.3048)
			(end 0.120396 0.3048)
			(stroke
				(width 0.1)
				(type default)
			)
			(layer "F.Fab")
		)
		(pad "1" smd circle
			(at -0.40005 0)
			(size 0 0)
			(layers "F.Cu" "F.Mask" "F.Paste")
			(net "HP_LVC3_OCP_V3_1_PRSNT2_N_R")
		)
		(pad "2" smd circle
			(at 0.40005 0)
			(size 0 0)
			(layers "F.Cu" "F.Mask" "F.Paste")
			(net "HP_LVC3_OCP_V3_1_ATTN_OUT_SW_N")
		)
	)
	(footprint ""
		(layer "F.Cu")
		(at 461.459834 -347.699838)
		(property "Reference" "H98"
			(at -6.703314 -4.139692 0)
			(unlocked yes)
			(layer "F.SilkS")
			(effects
				(font
					(size 0.7874 0.5842)
					(thickness 0.1524)
				)
				(justify left)
			)
		)
		(property "Value" ""
			(at 0 0 0)
			(layer "F.Fab")
			(effects
				(font
					(size 1.27 1.27)
				)
			)
		)
		(duplicate_pad_numbers_are_jumpers no)
		(pad "1" thru_hole circle
			(at 0 0)
			(size 10.0076 10.0076)
			(drill 5.6134)
			(layers "*.Cu" "*.Mask")
			(remove_unused_layers no)
			(net "GND")
			(clearance -1.9431)
		)
	)
	(footprint ""
		(layer "F.Cu")
		(at 18.302478 -17.623536 90)
		(property "Reference" "C808"
			(at 0 0 90)
			(layer "F.SilkS")
			(hide yes)
			(effects
				(font
					(size 1.27 1.27)
				)
			)
		)
		(property "Value" ""
			(at 0 0 90)
			(layer "F.Fab")
			(effects
				(font
					(size 1.27 1.27)
				)
			)
		)
		(duplicate_pad_numbers_are_jumpers no)
		(fp_line
			(start 0.299974 -0.150114)
			(end 0.299974 0.150114)
			(stroke
				(width 0.1)
				(type default)
			)
			(layer "F.Fab")
		)
		(fp_line
			(start -0.299974 -0.150114)
			(end 0.299974 -0.150114)
			(stroke
				(width 0.1)
				(type default)
			)
			(layer "F.Fab")
		)
		(fp_line
			(start 0.299974 0.150114)
			(end -0.299974 0.150114)
			(stroke
				(width 0.1)
				(type default)
			)
			(layer "F.Fab")
		)
		(fp_line
			(start -0.299974 0.150114)
			(end -0.299974 -0.150114)
			(stroke
				(width 0.1)
				(type default)
			)
			(layer "F.Fab")
		)
		(pad "1" smd rect
			(at -0.2667 0 90)
			(size 0.3048 0.381)
			(layers "F.Cu" "F.Mask" "F.Paste")
			(net "P5E_CPU1_PE1_TX_C_DN<14>")
		)
		(pad "2" smd rect
			(at 0.2667 0 90)
			(size 0.3048 0.381)
			(layers "F.Cu" "F.Mask" "F.Paste")
			(net "P5E_CPU1_PE1_TX_DN<14>")
		)
	)
)
